# T6G (Grand Teton) — schematic parts with pin connectivity, parts 8229–8229 of 8303; source: Cadence DE-HDL packaged netlist (pstxprt.dat, pstxnet.dat, pstchip.dat)

U6012  PT5161LRS  IC  pkg BGA354_8-9X22-8  page 296
  A1  NCF_GND1  POWER  = NCF_A1_CPU0_P2_GND
  A35  NCF_GND2  POWER  = NCF_CPU0_P2_GND
  AA10  B_PETN1  OUT  = P5E_CPU0_P2_TX_BUF_DN<14>
  AA29  A_PETN1  OUT  = P5E_CPU0_P2_RX_DN<14>
  AB1  A_PERP1  IN  = P5E_CPU0_P2_RX_BUF_DP<14>
  AB35  B_PERN1  IN  = P5E_CPU0_P2_TX_C_DP<14>
  AC4  GND4  POWER  = GND
  AC13  GND1  POWER  = GND
  AC17  PWR_2A_1  POWER  = P0V9_CPU0_RT2_2A
  AC20  PWR_2A_2  POWER  = P0V9_CPU0_RT2_2A
  AC22  GND2  POWER  = GND
  AC32  GND3  POWER  = GND
  AD2  GND5  POWER  = GND
  AD34  GND6  POWER  = GND
  AE1  GND7  POWER  = GND
  AE35  GND8  POWER  = GND
  AF7  B_PETP2  OUT  = P5E_CPU0_P2_TX_BUF_DP<13>
  AF26  A_PETP2  OUT  = P5E_CPU0_P2_RX_DP<13>
  AG2  A_PERN2  IN  = P5E_CPU0_P2_RX_BUF_DN<13>
  AG34  B_PERP2  IN  = P5E_CPU0_P2_TX_C_DN<13>
  AH10  B_PETN2  OUT  = P5E_CPU0_P2_TX_BUF_DN<13>
  AH29  A_PETN2  OUT  = P5E_CPU0_P2_RX_DN<13>
  AJ1  A_PERP2  IN  = P5E_CPU0_P2_RX_BUF_DP<13>
  AJ35  B_PERN2  IN  = P5E_CPU0_P2_TX_C_DP<13>
  AK4  GND12  POWER  = GND
  AK13  GND9  POWER  = GND
  AK17  PWR_2A_3  POWER  = P0V9_CPU0_RT2_2A
  AK20  PWR_2A_4  POWER  = P0V9_CPU0_RT2_2A
  AK22  GND10  POWER  = GND
  AK32  GND11  POWER  = GND
  AL2  GND13  POWER  = GND
  AL34  GND14  POWER  = GND
  AM1  GND15  POWER  = GND
  AM35  GND16  POWER  = GND
  AN7  B_PETP3  OUT  = P5E_CPU0_P2_TX_BUF_DP<12>
  AN26  A_PETP3  OUT  = P5E_CPU0_P2_RX_DP<12>
  AP2  A_PERN3  IN  = P5E_CPU0_P2_RX_BUF_DN<12>
  AP34  B_PERP3  IN  = P5E_CPU0_P2_TX_C_DN<12>
  AR10  B_PETN3  OUT  = P5E_CPU0_P2_TX_BUF_DN<12>
  AR29  A_PETN3  OUT  = P5E_CPU0_P2_RX_DN<12>
  AT1  A_PERP3  IN  = P5E_CPU0_P2_RX_BUF_DP<12>
  AT35  B_PERN3  IN  = P5E_CPU0_P2_TX_C_DP<12>
  AU4  GND20  POWER  = GND
  AU13  GND17  POWER  = GND
  AU17  PWR_2A_5  POWER  = P0V9_CPU0_RT2_2A
  AU20  PWR_2A_6  POWER  = P0V9_CPU0_RT2_2A
  AU22  GND18  POWER  = GND
  AU32  GND19  POWER  = GND
  AV2  GND21  POWER  = GND
  AV34  GND22  POWER  = GND
  AW1  GND23  POWER  = GND
  AW35  GND24  POWER  = GND
  AY7  B_PETP4  OUT  = P5E_CPU0_P2_TX_BUF_DP<11>
  AY26  A_PETP4  OUT  = P5E_CPU0_P2_RX_DP<11>
  B3  JTAG_TCK  IN  = JTAG_TCK_RT_CPU0_P2
  B6  JTAG_TDI  IN  = JTAG_TDI_RT_CPU0_P2
  B9  JTAG_TDO  OUT  = JTAG_TDO_RT_CPU0_P2
  B12  JTAG_TMS  IN  = JTAG_TMS_RT_CPU0_P2
  B16  REFCLK_OUTP  OUT  = NC
  B19  GND25  POWER  = GND
  B23  SMB_ADDR2  IN  = RT_CPU0_P2_ADDR2
  B25  SMB_ADDR3  IN  = RT_CPU0_P2_ADDR3
  B28  SMBDAT  BI  = SMB_RT_CPU0_P2_R2_SDA
  B31  SMBCLK  BI  = SMB_RT_CPU0_P2_R2_SCL
  BA2  A_PERN4  IN  = P5E_CPU0_P2_RX_BUF_DN<11>
  BA34  B_PERP4  IN  = P5E_CPU0_P2_TX_C_DN<11>
  BB10  B_PETN4  OUT  = P5E_CPU0_P2_TX_BUF_DN<11>
  BB29  A_PETN4  OUT  = P5E_CPU0_P2_RX_DN<11>
  BC1  A_PERP4  IN  = P5E_CPU0_P2_RX_BUF_DP<11>
  BC35  B_PERN4  IN  = P5E_CPU0_P2_TX_C_DP<11>
  BD4  GND29  POWER  = GND
  BD13  GND26  POWER  = GND
  BD17  PWR_2A_7  POWER  = P0V9_CPU0_RT2_2A_2D
  BD20  PWR_2A_8  POWER  = P0V9_CPU0_RT2_2A_2D
  BD22  GND27  POWER  = GND
  BD32  GND28  POWER  = GND
  BE2  GND30  POWER  = GND
  BE34  GND31  POWER  = GND
  BF1  GND32  POWER  = GND
  BF35  GND33  POWER  = GND
  BG7  B_PETP5  OUT  = P5E_CPU0_P2_TX_BUF_DP<10>
  BG26  A_PETP5  OUT  = P5E_CPU0_P2_RX_DP<10>
  BH2  A_PERN5  IN  = P5E_CPU0_P2_RX_BUF_DN<10>
  BH34  B_PERP5  IN  = P5E_CPU0_P2_TX_C_DN<10>
  BJ10  B_PETN5  OUT  = P5E_CPU0_P2_TX_BUF_DN<10>
  BJ29  A_PETN5  OUT  = P5E_CPU0_P2_RX_DN<10>
  BK1  A_PERP5  IN  = P5E_CPU0_P2_RX_BUF_DP<10>
  BK35  B_PERN5  IN  = P5E_CPU0_P2_TX_C_DP<10>
  BL4  GND37  POWER  = GND
  BL13  GND34  POWER  = GND
  BL17  PWR_2D_1  POWER  = P0V9_CPU0_RT_2D
  BL20  PWR_2D_2  POWER  = P0V9_CPU0_RT_2D
  BL22  GND35  POWER  = GND
  BL32  GND36  POWER  = GND
  BM2  GND38  POWER  = GND
  BM34  GND39  POWER  = GND
  BN1  GND40  POWER  = GND
  BN35  GND41  POWER  = GND
  BP7  B_PETP6  OUT  = P5E_CPU0_P2_TX_BUF_DP<9>
  BP26  A_PETP6  OUT  = P5E_CPU0_P2_RX_DP<9>
  BR2  A_PERN6  IN  = P5E_CPU0_P2_RX_BUF_DN<9>
  BR34  B_PERP6  IN  = P5E_CPU0_P2_TX_C_DN<9>
  BT10  B_PETN6  OUT  = P5E_CPU0_P2_TX_BUF_DN<9>
  BT29  A_PETN6  OUT  = P5E_CPU0_P2_RX_DN<9>
  BU1  A_PERP6  IN  = P5E_CPU0_P2_RX_BUF_DP<9>
  BU35  B_PERN6  IN  = P5E_CPU0_P2_TX_C_DP<9>
  BV4  GND45  POWER  = GND
  BV13  GND42  POWER  = GND
  BV17  PWR_1D  POWER  = P1V8_CPU0_RT2_1A_1D
  BV20  PWR_1A_1  POWER  = P1V8_CPU0_RT2_1A
  BV22  GND43  POWER  = GND
  BV32  GND44  POWER  = GND
  BW2  GND46  POWER  = GND
  BW34  GND47  POWER  = GND
  BY1  GND48  POWER  = GND
  BY35  GND49  POWER  = GND
  C2  NCF_GND3  POWER  = NCF_CPU0_P2_GND
  C34  NCF_GND4  POWER  = NCF_CPU0_P2_GND
  CA7  B_PETP7  OUT  = P5E_CPU0_P2_TX_BUF_DP<8>
  CA26  A_PETP7  OUT  = P5E_CPU0_P2_RX_DP<8>
  CB2  A_PERN7  IN  = P5E_CPU0_P2_RX_BUF_DN<8>
  CB34  B_PERP7  IN  = P5E_CPU0_P2_TX_C_DN<8>
  CC10  B_PETN7  OUT  = P5E_CPU0_P2_TX_BUF_DN<8>
  CC29  A_PETN7  OUT  = P5E_CPU0_P2_RX_DN<8>
  CD1  A_PERP7  IN  = P5E_CPU0_P2_RX_BUF_DP<8>
  CD35  B_PERN7  IN  = P5E_CPU0_P2_TX_C_DP<8>
  CE4  GND53  POWER  = GND
  CE13  GND50  POWER  = GND
  CE17  PWR_1A_2  POWER  = P1V8_CPU0_RT2_1A
  CE20  PWR_1A_3  POWER  = P1V8_CPU0_RT2_1A
  CE22  GND51  POWER  = GND
  CE32  GND52  POWER  = GND
  CF2  GND54  POWER  = GND
  CF34  GND55  POWER  = GND
  CG1  GND56  POWER  = GND
  CG35  GND57  POWER  = GND
  CH7  B_PETP8  OUT  = P5E_CPU0_P2_TX_BUF_DP<7>
  CH26  A_PETP8  OUT  = P5E_CPU0_P2_RX_DP<7>
  CJ2  A_PERN8  IN  = P5E_CPU0_P2_RX_BUF_DN<7>
  CJ34  B_PERP8  IN  = P5E_CPU0_P2_TX_C_DN<7>
  CK10  B_PETN8  OUT  = P5E_CPU0_P2_TX_BUF_DN<7>
  CK29  A_PETN8  OUT  = P5E_CPU0_P2_RX_DN<7>
  CL1  A_PERP8  IN  = P5E_CPU0_P2_RX_BUF_DP<7>
  CL35  B_PERN8  IN  = P5E_CPU0_P2_TX_C_DP<7>
  CM4  GND61  POWER  = GND
  CM13  GND58  POWER  = GND
  CM17  PWR_1A_4  POWER  = P1V8_CPU0_RT2_1A
  CM20  PWR_1A_5  POWER  = P1V8_CPU0_RT2_1A
  CM22  GND59  POWER  = GND
  CM32  GND60  POWER  = GND
  CN2  GND62  POWER  = GND
  CN34  GND63  POWER  = GND
  CP1  GND64  POWER  = GND
  CP35  GND65  POWER  = GND
  CR7  B_PETP9  OUT  = P5E_CPU0_P2_TX_BUF_DP<6>
  CR26  A_PETP9  OUT  = P5E_CPU0_P2_RX_DP<6>
  CT2  A_PERN9  IN  = P5E_CPU0_P2_RX_BUF_DN<6>
  CT34  B_PERP9  IN  = P5E_CPU0_P2_TX_C_DN<6>
  CU10  B_PETN9  OUT  = P5E_CPU0_P2_TX_BUF_DN<6>
  CU29  A_PETN9  OUT  = P5E_CPU0_P2_RX_DN<6>
  CV1  A_PERP9  IN  = P5E_CPU0_P2_RX_BUF_DP<6>
  CV35  B_PERN9  IN  = P5E_CPU0_P2_TX_C_DP<6>
  CW4  GND69  POWER  = GND
  CW13  GND66  POWER  = GND
  CW17  PWR_2D_3  POWER  = P0V9_CPU0_RT_2D
  CW20  PWR_2D_4  POWER  = P0V9_CPU0_RT_2D
  CW22  GND67  POWER  = GND
  CW32  GND68  POWER  = GND
  CY2  GND70  POWER  = GND
  CY34  GND71  POWER  = GND
  D1  NCF_GND5  POWER  = NCF_CPU0_P2_GND
  D35  NCF_GND6  POWER  = NCF_CPU0_P2_GND
  DA1  GND72  POWER  = GND
  DA35  GND73  POWER  = GND
  DB7  B_PETP10  OUT  = P5E_CPU0_P2_TX_BUF_DP<5>
  DB26  A_PETP10  OUT  = P5E_CPU0_P2_RX_DP<5>
  DC2  A_PERN10  IN  = P5E_CPU0_P2_RX_BUF_DN<5>
  DC34  B_PERP10  IN  = P5E_CPU0_P2_TX_C_DN<5>
  DD10  B_PETN10  OUT  = P5E_CPU0_P2_TX_BUF_DN<5>
  DD29  A_PETN10  OUT  = P5E_CPU0_P2_RX_DN<5>
  DE1  A_PERP10  IN  = P5E_CPU0_P2_RX_BUF_DP<5>
  DE35  B_PERN10  IN  = P5E_CPU0_P2_TX_C_DP<5>
  DF4  GND77  POWER  = GND
  DF13  GND74  POWER  = GND
  DF17  PWR_2A_9  POWER  = P0V9_CPU0_RT2_2A_2D
  DF20  PWR_2A_10  POWER  = P0V9_CPU0_RT2_2A_2D
  DF22  GND75  POWER  = GND
  DF32  GND76  POWER  = GND
  DG2  GND78  POWER  = GND
  DG34  GND79  POWER  = GND
  DH1  GND80  POWER  = GND
  DH35  GND81  POWER  = GND
  DJ7  B_PETP11  OUT  = P5E_CPU0_P2_TX_BUF_DP<4>
  DJ26  A_PETP11  OUT  = P5E_CPU0_P2_RX_DP<4>
  DK2  A_PERN11  IN  = P5E_CPU0_P2_RX_BUF_DN<4>
  DK34  B_PERP11  IN  = P5E_CPU0_P2_TX_C_DN<4>
  DL10  B_PETN11  OUT  = P5E_CPU0_P2_TX_BUF_DN<4>
  DL29  A_PETN11  OUT  = P5E_CPU0_P2_RX_DN<4>
  DM1  A_PERP11  IN  = P5E_CPU0_P2_RX_BUF_DP<4>
  DM35  B_PERN11  IN  = P5E_CPU0_P2_TX_C_DP<4>
  DN4  GND85  POWER  = GND
  DN13  GND82  POWER  = GND
  DN17  PWR_2A_11  POWER  = P0V9_CPU0_RT2_2A
  DN20  PWR_2A_12  POWER  = P0V9_CPU0_RT2_2A
  DN22  GND83  POWER  = GND
  DN32  GND84  POWER  = GND
  DP2  GND86  POWER  = GND
  DP34  GND87  POWER  = GND
  DR1  GND88  POWER  = GND
  DR35  GND89  POWER  = GND
  DT7  B_PETP12  OUT  = P5E_CPU0_P2_TX_BUF_DP<3>
  DT26  A_PETP12  OUT  = P5E_CPU0_P2_RX_DP<3>
  DU2  A_PERN12  IN  = P5E_CPU0_P2_RX_BUF_DN<3>
  DU34  B_PERP12  IN  = P5E_CPU0_P2_TX_C_DN<3>
  DV10  B_PETN12  OUT  = P5E_CPU0_P2_TX_BUF_DN<3>
  DV29  A_PETN12  OUT  = P5E_CPU0_P2_RX_DN<3>
  DW1  A_PERP12  IN  = P5E_CPU0_P2_RX_BUF_DP<3>
  DW35  B_PERN12  IN  = P5E_CPU0_P2_TX_C_DP<3>
  DY4  GND93  POWER  = GND
  DY13  GND90  POWER  = GND
  DY17  PWR_2A_13  POWER  = P0V9_CPU0_RT2_2A
  DY20  PWR_2A_14  POWER  = P0V9_CPU0_RT2_2A
  DY22  GND91  POWER  = GND
  DY32  GND92  POWER  = GND
  E8  JTAG_TRST_N  IN  = JTAG_TRST_RT_CPU0_P2_N
  E11  RXDET_BYP  IN  = RXDET_BYP_RT_CPU0_P2
  E14  GND94  POWER  = GND
  E18  REFCLK_OUTN  OUT  = NC
  E27  GND95  POWER  = GND
  E30  T_SENSE  OUT  = GND
  E33  GND96  POWER  = GND
  EA2  GND97  POWER  = GND
  EA34  GND98  POWER  = GND
  EB1  GND99  POWER  = GND
  EB35  GND100  POWER  = GND
  EC7  B_PETP13  OUT  = P5E_CPU0_P2_TX_BUF_DP<2>
  EC26  A_PETP13  OUT  = P5E_CPU0_P2_RX_DP<2>
  ED2  A_PERN13  IN  = P5E_CPU0_P2_RX_BUF_DN<2>
  ED34  B_PERP13  IN  = P5E_CPU0_P2_TX_C_DN<2>
  EE10  B_PETN13  OUT  = P5E_CPU0_P2_TX_BUF_DN<2>
  EE29  A_PETN13  OUT  = P5E_CPU0_P2_RX_DN<2>
  EF1  A_PERP13  IN  = P5E_CPU0_P2_RX_BUF_DP<2>
  EF35  B_PERN13  IN  = P5E_CPU0_P2_TX_C_DP<2>
  EG4  GND104  POWER  = GND
  EG13  GND101  POWER  = GND
  EG17  PWR_2A_15  POWER  = P0V9_CPU0_RT2_2A
  EG20  PWR_2A_16  POWER  = P0V9_CPU0_RT2_2A
  EG22  GND102  POWER  = GND
  EG32  GND103  POWER  = GND
  EH2  GND105  POWER  = GND
  EH34  GND106  POWER  = GND
  EJ1  GND107  POWER  = GND
  EJ35  GND108  POWER  = GND
  EK7  B_PETP14  OUT  = P5E_CPU0_P2_TX_BUF_DP<1>
  EK26  A_PETP14  OUT  = P5E_CPU0_P2_RX_DP<1>
  EL2  A_PERN14  IN  = P5E_CPU0_P2_RX_BUF_DN<1>
  EL34  B_PERP14  IN  = P5E_CPU0_P2_TX_C_DP<1>
  EM10  B_PETN14  OUT  = P5E_CPU0_P2_TX_BUF_DN<1>
  EM29  A_PETN14  OUT  = P5E_CPU0_P2_RX_DN<1>
  EN1  A_PERP14  IN  = P5E_CPU0_P2_RX_BUF_DP<1>
  EN35  B_PERN14  IN  = P5E_CPU0_P2_TX_C_DN<1>
  EP4  GND112  POWER  = GND
  EP13  GND109  POWER  = GND
  EP17  PWR_2A_17  POWER  = P0V9_CPU0_RT2_2A
  EP20  PWR_2A_18  POWER  = P0V9_CPU0_RT2_2A
  EP22  GND110  POWER  = GND
  EP32  GND111  POWER  = GND
  ER2  GND113  POWER  = GND
  ER34  GND114  POWER  = GND
  ET1  GND115  POWER  = GND
  ET35  GND116  POWER  = GND
  EU7  B_PETP15  OUT  = P5E_CPU0_P2_TX_BUF_DP<0>
  EU26  A_PETP15  OUT  = P5E_CPU0_P2_RX_DP<0>
  EV2  A_PERN15  IN  = P5E_CPU0_P2_RX_BUF_DN<0>
  EV34  B_PERP15  IN  = P5E_CPU0_P2_TX_C_DN<0>
  EW10  B_PETN15  OUT  = P5E_CPU0_P2_TX_BUF_DN<0>
  EW29  A_PETN15  OUT  = P5E_CPU0_P2_RX_DN<0>
  EY1  A_PERP15  IN  = P5E_CPU0_P2_RX_BUF_DP<0>
  EY35  B_PERN15  IN  = P5E_CPU0_P2_TX_C_DP<0>
  F2  PERST_N  IN  = RST_RT_CPU0_P2_PERST_N
  F34  SMB_ADDR1  IN  = RT_CPU0_P2_ADDR1
  FA15  GND117  POWER  = GND
  FA32  GND118  POWER  = GND
  FB2  GND119  POWER  = GND
  FB34  GND120  POWER  = GND
  FC3  GND125  POWER  = GND
  FC6  GND126  POWER  = GND
  FC9  GND127  POWER  = GND
  FC19  GND121  POWER  = GND
  FC23  GND122  POWER  = GND
  FC25  GND123  POWER  = GND
  FC28  GND124  POWER  = GND
  FD1  GND128  POWER  = GND
  FD35  GND129  POWER  = GND
  FE2  NCF_GND7  POWER  = NCF_CPU0_P2_GND
  FE34  NCF_GND8  POWER  = NCF_CPU0_P2_GND
  FF5  EE_CLK  BI  = SMB_RT_CPU0_P2_ROM_MUX_1D_R_SCL
  FF8  JTAG_TEST_MODE  IN  = JTAG_TEST_MODE_RT_CPU0_P2
  FF11  RESET_N  IN  = RST_RT_CPU0_P2_RESET_N
  FF14  GND130  POWER  = GND
  FF18  REFCLKN  IN  = CLK_100M_RETIMER_CPU0_P2_DN
  FF21  GND131  POWER  = GND
  FF24  TEST0  BI  = TEST0_RT_CPU0_P2
  FF27  TEST1  BI  = TEST1_RT_CPU0_P2
  FF30  TEST2  BI  = TEST2_RT_CPU0_P2
  FF33  SCAN_MODE  IN  = RT_CPU0_P2_SCAN_MODE
  FG1  NCF_GND9  POWER  = NCF_CPU0_P2_GND
  FG35  NCF_GND10  POWER  = NCF_CPU0_P2_GND
  FH2  NCF_GND11  POWER  = NCF_CPU0_P2_GND
  FH34  NCF_GND12  POWER  = NCF_CPU0_P2_GND
  FJ3  EE_DAT  BI  = SMB_RT_CPU0_P2_ROM_MUX_1D_R_SDA
  FJ6  GPIO0  BI  = NC
  FJ9  MODE  IN  = MODE_RT_CPU0_P2
  FJ12  GND132  POWER  = GND
  FJ16  REFCLKP  IN  = CLK_100M_RETIMER_CPU0_P2_DP
  FJ19  GND133  POWER  = GND
  FJ23  GPIO1  BI  = NC
  FJ25  GPIO2  BI  = GPIO2_RT_CPU0_P2
  FJ28  GPIO3  BI  = GPIO3_RT_CPU0_P2
  FJ31  INT_N  OUT  = NC
  G1  VQPS  IN  = RT_CPU0_P2_VQPS
  G35  CLKREQ_N  IN  = CLKREQ_RT_CPU0_P2_N
  H12  GND134  POWER  = GND
  H16  GND135  POWER  = GND
  H19  GND136  POWER  = GND
  H31  GND137  POWER  = GND
  J4  GND139  POWER  = GND
  J22  GND138  POWER  = GND
  K2  GND140  POWER  = GND
  K34  GND141  POWER  = GND
  L1  GND142  POWER  = GND
  L35  GND143  POWER  = GND
  M7  B_PETP0  OUT  = P5E_CPU0_P2_TX_BUF_DP<15>
  M26  A_PETP0  OUT  = P5E_CPU0_P2_RX_DP<15>
  N2  A_PERN0  IN  = P5E_CPU0_P2_RX_BUF_DN<15>
  N34  B_PERP0  IN  = P5E_CPU0_P2_TX_C_DN<15>
  P10  B_PETN0  OUT  = P5E_CPU0_P2_TX_BUF_DN<15>
  P29  A_PETN0  OUT  = P5E_CPU0_P2_RX_DN<15>
  R1  A_PERP0  IN  = P5E_CPU0_P2_RX_BUF_DP<15>
  R35  B_PERN0  IN  = P5E_CPU0_P2_TX_C_DP<15>
  T4  GND147  POWER  = GND
  T13  GND144  POWER  = GND
  T17  PWR_2A_19  POWER  = P0V9_CPU0_RT2_2A
  T20  PWR_2A_20  POWER  = P0V9_CPU0_RT2_2A
  T22  GND145  POWER  = GND
  T32  GND146  POWER  = GND
  U2  GND148  POWER  = GND
  U34  GND149  POWER  = GND
  V1  GND150  POWER  = GND
  V35  GND151  POWER  = GND
  W7  B_PETP1  OUT  = P5E_CPU0_P2_TX_BUF_DP<14>
  W26  A_PETP1  OUT  = P5E_CPU0_P2_RX_DP<14>
  Y2  A_PERN1  IN  = P5E_CPU0_P2_RX_BUF_DN<14>
  Y34  B_PERP1  IN  = P5E_CPU0_P2_TX_C_DN<14>
